# SA800U (Snapdragon 845) Baseboard — footprint library table
(fp_lib_table
  (lib (name "sa800u-baseboard-hw-footprints")(type "KiCad")(uri "${KIPRJMOD}/lib/sa800u-baseboard-hw-footprints")(options "")(descr ""))
)
